# 2Slot_Riser Card_BOM.xlsx — 2 slot riser (bom)
| Description | Qty | UoM | Location |
| TP PCIE RISER CARD SS-2 BT 2ND(D)-1A | 1 | PCS |  |
| LABEL POLYESTER 25.4*6.35MM | 1 | PCS | LABEL3 |
| LBL POLYIMIDE31.8*6.35 BARCODE | 2 | PCS | LABEL1 LABEL2 |
| TP PCIE RISER CARD SS-2 BT 2ND(S)-1A | 1 | PCS | SMT |
| CONN CTR 4P C23118-P04C0-L, PA9T | 1 | PCS | CN2 |
| SKT EDGE PCIE 164P APCI0254-P002C | 2 | PCS | SLOT2 SLOT3 |
| CHIP BEAD BCMS201209A220 | 1 | PCS | PL1 |
| IC USB CTRL USB2513B/M2 QFN 36P | 1 | PCS | U22 |
| IC I2C SW TCA9544APWR TSSOP 20P | 2 | PCS | U1 U2 |
| IC I/O EXPANDER TCA9555PWR TSSOP 24P | 2 | PCS | U20 U21 |
| IC CONV 12A MPQ8633AGLE QFN 21P | 1 | PCS | PU1 |
| IC FETMOS DMN63D1LDW-7 NC SOT-363 ESD 2K | 1 | PCS | Q1 |
| CHIP CAP C 10UF 6.3V M 0603 X6S | 2 | PCS | C20 C26 |
| CHIP CAP C 22U 16V M0805 X6S | 6 | PCS | C54 C88 C89 C90 PC1 PC2 |
| CHIP RES 0 J 1/4W 1206 (ROHS) | 1 | PCS | R203 |
| CHIP RES 100 F 1/16W 0402 | 1 | PCS | R119 |
| CHIP RES 10K F 1/16W 0402 | 32 | PCS | PR3 PR4 R113 R114 R117 R12 R14 R142 R144 R145 R148 R15 R151 R18 R27 R39 R52 R54 R55 R58 R59 R64 R67 R68 R84 R9 R92 R94 R95 RU22 RU26 RU29 |
| CHIP RES 100K F 1/16W 0402 | 1 | PCS | RU25 |
| CHIP RES 10 F 1/10W 0603 | 1 | PCS | PR2 |
| CHIP RES 10 F 1/16W 0402 | 6 | PCS | R80 R81 R86 R87 R96 R98 |
| CHIP RES 12K F 1/16W 0402 | 1 | PCS | RU24 |
| CHIP RES 19.6K F 1/16W 0402 | 1 | PCS | PR8 |
| CHIP RES 2.2K F 1/16W 0402 | 1 | PCS | PR5 |
| CHIP RES 30.1K F 1/16W 0402 | 1 | PCS | PR6 |
| CHIP RES 3.3K F 1/16W 0402 | 1 | PCS | R43 |
| CHIP RES 3.74K F 1/16W 0402 | 1 | PCS | PR9 |
| CHIP RES 4.7K F 1/16W 0402 | 28 | PCS | R10 R102 R103 R104 R105 R106 R107 R108 R11 R120 R167 R19 R20 R201 R202 R21 R22 R23 R24 R25 R26 R3 R4 R5 R6 R7 R79 R8 |
| CHIP RES 475 F 1/16W 0402 | 2 | PCS | R1 R2 |
| CHIP RES 8.2K F 1/16W 0402 | 1 | PCS | R65 |
| CHIP RES 8.87K F 1/16W 0402 | 1 | PCS | PR7 |
| CHIP RES 0 F 1/16W 0402 | 41 | PCS | R100 R101 R164 R165 R166 R168 R169 R170 R173 R28 R29 R30 R31 R32 R33 R34 R35 R36 R37 R40 R41 R42 R45 R47 R48 R49 R60 R61 R63 R69 R70 R71 R73 R78 R88 R89 R97 R99 RU7 RU8 RU9 |
| CHIP RES 0.001 F 1W 1206 | 3 | PCS | R109 R83 R90 |
| CHIP BEAD FCM1608KF-301T05 | 1 | PCS | LU1 |
| CHIP CHOKE 1.5UH M PCMB065T-1R5MS | 1 | PCS | PL2 |
| IC REPEATER PCA9517ADP TSSOP 8P | 1 | PCS | U23 |
| IC CMOS 74LVC1G08GW,125 SOT-353(LF) | 2 | PCS | U10 U8 |
| IC POWER MONITOR INA230AIRGTR QFN 16P | 3 | PCS | U14 U15 U16 |
| IC RESET ADM809SARTZ-REEL7 SOT-23 | 1 | PCS | U5 |
| CHIP CAP C 0.01U 16V K0402 X7R | 1 | PCS | C37 |
| CHIP CAP C 0.1U 16V K0603 X7R | 1 | PCS | PC5 |
| CHIP CAP C 0.1U 16V K0402 X7R | 21 | PCS | C17 C18 C19 C21 C22 C23 C24 C27 C33 C34 C41 C42 C48 C50 C52 C57 C58 C59 CU13 PC15 PC3 |
| CHIP CAP C 0.1U 25V K0603 X7R | 9 | PCS | C13 C14 C15 C16 C25 C28 C29 C30 C36 |
| CHIP CAP C 0.1U 25V K0402 X7R | 6 | PCS | C47 C49 C51 C53 C55 C56 |
| CHIP CAP C 0.1U 50V K0603 X7R | 1 | PCS | PC4 |
| CHIP CAP C 1U 6.3V K0603 X7R | 1 | PCS | CU2 |
| CHIP CAP C 1U 10V K 0402 X6S | 8 | PCS | CU10 CU3 CU4 CU5 CU6 CU7 CU8 CU9 |
| CHIP CAP C 10U 6.3V K0805 X7R | 1 | PCS | C32 |
| CHIP CAP C 18P 50V J0402 NP0 | 2 | PCS | CU11 CU12 |
| CHIP CAP 0.022U 16V K0402 X7R | 1 | PCS | PC11 |
| CHIP CAP C 2.2U 10V K0603 X7R | 3 | PCS | C61 PC12 PC13 |
| CHIP CAP C 22U 6.3V M0805 X6S | 4 | PCS | PC6 PC7 PC8 PC9 |
| CHIP CAP C 270P 50V K0402 X7R | 1 | PCS | PC10 |
| CHIP CAP 100U25V EEEFK1E101XP | 4 | PCS | TC1 TC2 TC3 TC4 |
| XTAL 24MHZ 12PF 20PPM SMD | 1 | PCS | XU1 |
| PCB 15968-1A DVT RISER CARD_SS 2SLO 6L B | 1 | PCS | PCB |
| DP TIOGA PASS PCIE RISER CARD-SA | 1 | PCS |  |
| DESICANT SILICA GEL 30G H25 | 0.044 | PCS |  |
| LBL CAUTION FOR P97AE | 1 | PCS |  |
| BAG PE ESD 127*204MM (15058) | 1 | PCS |  |
| LBL CTN ART 124*40 B/W ALL | 0.022 | PCS |  |
| CORNER KRAFT PAPER 900*50*50*3 | 0.002 | PCS |  |
| CORNER PAPER 700*50*50*3MM | 0.004 | PCS |  |
| CORNER PAPER1100*50*50*3 ORIGI | 0.002 | PCS |  |
| SHEET AB FLUTE 1200*1000 NS110 | 0.001 | PCS |  |
| PAD B 475*375MM | 0.022 | PCS |  |
| PALLET PLYWOOD 1200*1000*114MM | 0.001 | PCS |  |
| CTN_500X400X200_BP_RISERCARD_LEOPARD_BW | 0.022 | PCS |  |
| P-PAD SIDE_379X170_RISERCARD_LEOPARD_BW | 0.133 | PCS |  |
| P-PAD FRONT_479X170_RISERCARD_LEOPARD_BW | 0.222 | PCS |  |
| Description | Qty | UoM | Location |
